# TIMECARD (Time Appliance Project (Time Card)) — schematic netlist excerpt (pin names and nets, part order shuffled) for the footprints in the layout excerpt that follows; sources: Cadence DE-HDL packaged netlist, KiCad conversion of R4006-B0001-02_R01.brd

R127  RESISTOR  49.9OHM 1%  pkg SMC_0402R_H016  page 23 : \1\ = BF_SMA1_SIG_IO_CONN ; \2\ = SMA1_SIG_IO_CONN
TP32  TP_PIONT  pkg TP010CT020B030_PTH  page 25 : \1\ = SMA1_SIG_OUT_BF_EN_N
TP196  TP_PIONT  pkg TP010CT020B030_PTH  page 25 : \1\ = IO_L23N_35

(kicad_pcb
	(version 20260206)
	(generator "pcbnew")
	(generator_version "10.0")
	(general
		(thickness 1.6)
		(legacy_teardrops no)
	)
	(paper "A4")
	(title_block
		(title "timecard-production-celestica-r4006 — R4006-B0001-02_R01.brd")
		(comment 1 "Time Appliance Project (Time Card) / footprints 491-493 of 1113")
	)
	(layers
		(0 "F.Cu" signal "TOP")
		(4 "In1.Cu" signal "L02_GND1")
		(6 "In2.Cu" signal "L03_SIG1")
		(8 "In3.Cu" signal "L04_GND2")
		(10 "In4.Cu" signal "L05_VCC1")
		(12 "In5.Cu" signal "L06_VCC2")
		(14 "In6.Cu" signal "L07_GND3")
		(16 "In7.Cu" signal "L08_SIG2")
		(18 "In8.Cu" signal "L09_GND4")
		(2 "B.Cu" signal "BOTTOM")
		(9 "F.Adhes" user "F.Adhesive")
		(11 "B.Adhes" user "B.Adhesive")
		(13 "F.Paste" user "Package Geometry/Pastemask Top")
		(15 "B.Paste" user "Package Geometry/Pastemask Bottom")
		(5 "F.SilkS" user "Ref Des/Silkscreen Top")
		(7 "B.SilkS" user "Ref Des/Silkscreen Bottom")
		(1 "F.Mask" user "Board Geometry/Soldermask Top")
		(3 "B.Mask" user "Board Geometry/Soldermask Bottom")
		(17 "Dwgs.User" user "User.Drawings")
		(19 "Cmts.User" user "User.Comments")
		(21 "Eco1.User" user "User.Eco1")
		(23 "Eco2.User" user "User.Eco2")
		(25 "Edge.Cuts" user "Board Geometry/Outline")
		(27 "Margin" user)
		(31 "F.CrtYd" user "Package Geometry/Place Bound Top")
		(29 "B.CrtYd" user "Package Geometry/Place Bound Bottom")
		(35 "F.Fab" user "Ref Des/Assembly Top")
		(33 "B.Fab" user "Ref Des/Assembly Bottom")
	)
	(footprint ""
		(layer "F.Cu")
		(at 11.798808 -57.2516 -90)
		(property "Reference" "R127"
			(at 0.3556 2.107438 90)
			(unlocked yes)
			(layer "F.SilkS")
			(effects
				(font
					(size 0.7874 0.5842)
					(thickness 0.1524)
				)
			)
		)
		(property "Value" "VAL*"
			(at 0.02032 2.13233 270)
			(unlocked yes)
			(layer "F.Fab")
			(hide yes)
			(effects
				(font
					(size 0.7874 0.5842)
					(thickness 0.1524)
				)
			)
		)
		(property "Tolerance" "TOL*"
			(at 0.044704 3.05435 270)
			(unlocked yes)
			(layer "Cmts.User")
			(hide yes)
			(effects
				(font
					(size 0.7874 0.5842)
					(thickness 0.1524)
				)
			)
		)
		(property "User Part Number" "PARTNUM*"
			(at 0.02032 4.024884 270)
			(unlocked yes)
			(layer "Cmts.User")
			(hide yes)
			(effects
				(font
					(size 0.7874 0.5842)
					(thickness 0.1524)
				)
			)
		)
		(property "Device Type" "RESISTOR-G155-149R9-01,49.9OHMA"
			(at 0.008382 1.210564 270)
			(unlocked yes)
			(layer "F.Fab")
			(hide yes)
			(effects
				(font
					(size 0.7874 0.5842)
					(thickness 0.1524)
				)
			)
		)
		(duplicate_pad_numbers_are_jumpers no)
		(fp_line
			(start -1.143 0.5588)
			(end 1.143 0.5588)
			(stroke
				(width 0.1)
				(type default)
			)
			(layer "F.SilkS")
		)
		(fp_line
			(start 1.143 0.5588)
			(end 1.143 -0.5588)
			(stroke
				(width 0.1)
				(type default)
			)
			(layer "F.SilkS")
		)
		(fp_line
			(start -1.143 -0.5588)
			(end -1.143 0.5588)
			(stroke
				(width 0.1)
				(type default)
			)
			(layer "F.SilkS")
		)
		(fp_line
			(start 1.143 -0.5588)
			(end -1.143 -0.5588)
			(stroke
				(width 0.1)
				(type default)
			)
			(layer "F.SilkS")
		)
		(fp_poly
			(pts
				(xy -1.143 0.5588) (xy 1.143 0.5588) (xy 1.143 -0.5588) (xy -1.143 -0.5588)
			)
			(stroke
				(width 0)
				(type default)
			)
			(fill no)
			(layer "F.CrtYd")
		)
		(fp_line
			(start -0.508 0.3048)
			(end 0.508 0.3048)
			(stroke
				(width 0.1)
				(type default)
			)
			(layer "F.Fab")
		)
		(fp_line
			(start 0.508 0.3048)
			(end 0.508 -0.3048)
			(stroke
				(width 0.1)
				(type default)
			)
			(layer "F.Fab")
		)
		(fp_line
			(start -0.508 -0.3048)
			(end -0.508 0.3048)
			(stroke
				(width 0.1)
				(type default)
			)
			(layer "F.Fab")
		)
		(fp_line
			(start 0.508 -0.3048)
			(end -0.508 -0.3048)
			(stroke
				(width 0.1)
				(type default)
			)
			(layer "F.Fab")
		)
		(pad "1" smd rect
			(at -0.5334 0 270)
			(size 0.7112 0.6096)
			(layers "F.Cu" "F.Mask" "F.Paste")
			(net "BF_SMA1_SIG_IO_CONN")
		)
		(pad "2" smd rect
			(at 0.5334 0 270)
			(size 0.7112 0.6096)
			(layers "F.Cu" "F.Mask" "F.Paste")
			(net "SMA1_SIG_IO_CONN")
		)
		(zone
			(layer "F.Cu")
			(hatch none 0.5)
			(connect_pads
				(clearance 0)
			)
			(min_thickness 0.25)
			(keepout
				(tracks allowed)
				(vias not_allowed)
				(pads allowed)
				(copperpour not_allowed)
				(footprints allowed)
			)
			(placement
				(enabled no)
				(sheetname "")
			)
			(fill
				(thermal_gap 0.5)
				(thermal_bridge_width 0.5)
				(island_removal_mode 0)
			)
			(polygon
				(pts
					(xy 11.494008 -57.3278) (xy 11.494008 -57.1754) (xy 12.103608 -57.1754) (xy 12.103608 -57.3278)
				)
			)
		)
		(zone
			(layer "F.Cu")
			(hatch none 0.5)
			(connect_pads
				(clearance 0)
			)
			(min_thickness 0.25)
			(keepout
				(tracks not_allowed)
				(vias allowed)
				(pads allowed)
				(copperpour not_allowed)
				(footprints allowed)
			)
			(placement
				(enabled no)
				(sheetname "")
			)
			(fill
				(thermal_gap 0.5)
				(thermal_bridge_width 0.5)
				(island_removal_mode 0)
			)
			(polygon
				(pts
					(xy 11.494008 -57.3278) (xy 11.494008 -57.1754) (xy 12.103608 -57.1754) (xy 12.103608 -57.3278)
				)
			)
		)
	)
	(footprint ""
		(layer "F.Cu")
		(at 16.4338 -63.9318)
		(property "Reference" "TP32"
			(at -0.52705 3.1242 90)
			(unlocked yes)
			(layer "F.SilkS")
			(effects
				(font
					(size 0.635 0.4064)
					(thickness 0.1524)
				)
				(justify left)
			)
		)
		(property "Value" ""
			(at 0 0 0)
			(layer "F.Fab")
			(effects
				(font
					(size 1.27 1.27)
				)
			)
		)
		(property "Device Type" "TP_PIONT-TP010CT020B030_PTH-TPA"
			(at -1.341882 0.996696 0)
			(unlocked yes)
			(layer "F.Fab")
			(hide yes)
			(effects
				(font
					(size 0.7874 0.5842)
					(thickness 0.000001)
				)
				(justify left)
			)
		)
		(duplicate_pad_numbers_are_jumpers no)
		(fp_poly
			(pts
				(arc
					(start 0.889 0)
					(mid -0.889 0)
					(end 0.889 0)
				)
			)
			(stroke
				(width 0)
				(type default)
			)
			(fill no)
			(layer "B.CrtYd")
		)
		(fp_poly
			(pts
				(arc
					(start 0.889 0)
					(mid -0.889 0)
					(end 0.889 0)
				)
			)
			(stroke
				(width 0)
				(type default)
			)
			(fill no)
			(layer "F.CrtYd")
		)
		(pad "1" thru_hole circle
			(at 0 0)
			(size 0.508 0.508)
			(drill 0.254)
			(layers "*.Cu" "*.Mask")
			(remove_unused_layers no)
			(net "SMA1_SIG_OUT_BF_EN_N")
			(clearance 0.1016)
			(padstack
				(mode front_inner_back)
				(layer "Inner"
					(shape circle)
					(size 0.508 0.508)
					(clearance 0.1016)
				)
				(layer "B.Cu"
					(shape circle)
					(size 0.762 0.762)
					(clearance -0.0254)
				)
			)
		)
	)
	(footprint ""
		(layer "F.Cu")
		(at 106.299 -29.718 90)
		(property "Reference" "TP196"
			(at -1.5748 -0.85725 90)
			(unlocked yes)
			(layer "F.SilkS")
			(effects
				(font
					(size 0.635 0.4064)
					(thickness 0.1524)
				)
				(justify left)
			)
		)
		(property "Value" ""
			(at 0 0 90)
			(layer "F.Fab")
			(effects
				(font
					(size 1.27 1.27)
				)
			)
		)
		(property "Device Type" "TP_PIONT-TP010CT020B030_PTH-TPA"
			(at -1.341882 0.996696 90)
			(unlocked yes)
			(layer "F.Fab")
			(hide yes)
			(effects
				(font
					(size 0.7874 0.5842)
					(thickness 0.1524)
				)
				(justify left)
			)
		)
		(duplicate_pad_numbers_are_jumpers no)
		(fp_poly
			(pts
				(arc
					(start 0 0.889)
					(mid 0 -0.889)
					(end 0 0.889)
				)
			)
			(stroke
				(width 0)
				(type default)
			)
			(fill no)
			(layer "B.CrtYd")
		)
		(fp_poly
			(pts
				(arc
					(start 0 0.889)
					(mid 0 -0.889)
					(end 0 0.889)
				)
			)
			(stroke
				(width 0)
				(type default)
			)
			(fill no)
			(layer "F.CrtYd")
		)
		(pad "1" thru_hole circle
			(at 0 0 90)
			(size 0.508 0.508)
			(drill 0.254)
			(layers "*.Cu" "*.Mask")
			(remove_unused_layers no)
			(net "IO_L23N_35")
			(clearance 0.1016)
			(padstack
				(mode front_inner_back)
				(layer "Inner"
					(shape circle)
					(size 0.508 0.508)
					(clearance 0.1016)
				)
				(layer "B.Cu"
					(shape circle)
					(size 0.762 0.762)
					(clearance -0.0254)
				)
			)
		)
	)
)
